# T6G (Grand Teton) — schematic netlist excerpt (pin names and nets, part order shuffled) for the footprints in the layout excerpt that follows; sources: Cadence DE-HDL packaged netlist, KiCad conversion of 04192023_DAF0TMB3IC0_F0TG_MB_C_brd_V02_OCP.brd

R3669  Q_RES  1K 1% EMPTY  pkg 0402LF  page 257 : A = P3V3_AUX ; B = ADC128_A0

PD17  SS15P3SM386A  SS15P3S-M3/86A IC  pkg TO277A_4-3X6-1  page 266
  ANODE_1  = GND
  ANODE_2  = GND
  CATHODE  = P12V_AUX

(kicad_pcb
	(version 20260206)
	(generator "pcbnew")
	(generator_version "10.0")
	(general
		(thickness 1.6)
		(legacy_teardrops no)
	)
	(paper "A4")
	(title_block
		(title "04192023_DAF0TMB3IC0_F0TG_MB_C_brd_V02_OCP.brd")
		(comment 1 "Grand Teton / footprints 1951-1952 of 8354")
	)
	(layers
		(0 "F.Cu" signal "TOP")
		(4 "In1.Cu" signal "GND")
		(6 "In2.Cu" signal "IN1")
		(8 "In3.Cu" signal "GND1")
		(10 "In4.Cu" signal "IN2")
		(12 "In5.Cu" signal "GND2")
		(14 "In6.Cu" signal "IN3")
		(16 "In7.Cu" signal "GND3")
		(18 "In8.Cu" signal "VCC")
		(20 "In9.Cu" signal "VCC1")
		(22 "In10.Cu" signal "GND4")
		(24 "In11.Cu" signal "IN4")
		(26 "In12.Cu" signal "GND5")
		(28 "In13.Cu" signal "IN5")
		(30 "In14.Cu" signal "GND6")
		(32 "In15.Cu" signal "IN6")
		(34 "In16.Cu" signal "GND7")
		(2 "B.Cu" signal "BOTTOM")
		(9 "F.Adhes" user "F.Adhesive")
		(11 "B.Adhes" user "B.Adhesive")
		(13 "F.Paste" user "Package Geometry/Pastemask Top")
		(15 "B.Paste" user "Package Geometry/Pastemask Bottom")
		(5 "F.SilkS" user "Ref Des/Silkscreen Top")
		(7 "B.SilkS" user "Ref Des/Silkscreen Bottom")
		(1 "F.Mask" user "Board Geometry/Soldermask Top")
		(3 "B.Mask" user "Board Geometry/Soldermask Bottom")
		(17 "Dwgs.User" user "User.Drawings")
		(19 "Cmts.User" user "User.Comments")
		(21 "Eco1.User" user "User.Eco1")
		(23 "Eco2.User" user "User.Eco2")
		(25 "Edge.Cuts" user "Board Geometry/Outline")
		(27 "Margin" user)
		(31 "F.CrtYd" user "Package Geometry/Place Bound Top")
		(29 "B.CrtYd" user "Package Geometry/Place Bound Bottom")
		(35 "F.Fab" user "Ref Des/Assembly Top")
		(33 "B.Fab" user "Ref Des/Assembly Bottom")
	)
	(footprint ""
		(layer "F.Cu")
		(at 241.114834 -374.81129 90)
		(property "Reference" "PD17"
			(at 2.0574 -3.343148 90)
			(unlocked yes)
			(layer "F.SilkS")
			(effects
				(font
					(size 0.7874 0.5842)
					(thickness 0.1524)
				)
			)
		)
		(property "Value" ""
			(at 0 0 90)
			(layer "F.Fab")
			(effects
				(font
					(size 1.27 1.27)
				)
			)
		)
		(duplicate_pad_numbers_are_jumpers no)
		(fp_line
			(start 3.541776 -2.54)
			(end 3.541776 2.54)
			(stroke
				(width 0.1524)
				(type default)
			)
			(layer "F.SilkS")
		)
		(fp_line
			(start -3.539744 -2.54)
			(end 3.541776 -2.54)
			(stroke
				(width 0.1524)
				(type default)
			)
			(layer "F.SilkS")
		)
		(fp_line
			(start 3.541776 2.54)
			(end -3.539744 2.54)
			(stroke
				(width 0.1524)
				(type default)
			)
			(layer "F.SilkS")
		)
		(fp_line
			(start -3.539744 2.54)
			(end -3.539744 -2.54)
			(stroke
				(width 0.1524)
				(type default)
			)
			(layer "F.SilkS")
		)
		(fp_poly
			(pts
				(xy -2.86258 2.690876) (xy -2.35458 3.706876) (xy -3.37058 3.706876)
			)
			(stroke
				(width 0)
				(type default)
			)
			(fill yes)
			(layer "F.SilkS")
		)
		(fp_line
			(start 3.074924 -2.175002)
			(end 3.074924 2.175002)
			(stroke
				(width 0.1)
				(type default)
			)
			(layer "F.Fab")
		)
		(fp_line
			(start -3.074924 -2.175002)
			(end 3.074924 -2.175002)
			(stroke
				(width 0.1)
				(type default)
			)
			(layer "F.Fab")
		)
		(fp_line
			(start 3.074924 2.175002)
			(end -3.074924 2.175002)
			(stroke
				(width 0.1)
				(type default)
			)
			(layer "F.Fab")
		)
		(fp_line
			(start -3.074924 2.175002)
			(end -3.074924 -2.175002)
			(stroke
				(width 0.1)
				(type default)
			)
			(layer "F.Fab")
		)
		(fp_poly
			(pts
				(xy -4.699 0.531876) (xy -4.699 1.547876) (xy -3.683 1.039876)
			)
			(stroke
				(width 0)
				(type default)
			)
			(fill yes)
			(layer "F.Fab")
		)
		(pad "1" smd rect
			(at -2.765044 1.039876 270)
			(size 1.27 1.4224)
			(layers "F.Cu" "F.Mask" "F.Paste")
			(net "GND")
		)
		(pad "2" smd rect
			(at -2.765044 -1.039876 270)
			(size 1.27 1.4224)
			(layers "F.Cu" "F.Mask" "F.Paste")
			(net "GND")
		)
		(pad "K" smd rect
			(at 1.039876 0 270)
			(size 4.7244 4.8006)
			(layers "F.Cu" "F.Mask" "F.Paste")
			(net "P12V_AUX")
		)
	)
	(footprint ""
		(layer "F.Cu")
		(at 303.200308 -41.906698)
		(property "Reference" "R3669"
			(at 0 0 0)
			(layer "F.SilkS")
			(hide yes)
			(effects
				(font
					(size 1.27 1.27)
				)
			)
		)
		(property "Value" ""
			(at 0 0 0)
			(layer "F.Fab")
			(effects
				(font
					(size 1.27 1.27)
				)
			)
		)
		(duplicate_pad_numbers_are_jumpers no)
		(fp_line
			(start -0.7874 -0.4064)
			(end 0.7874 -0.4064)
			(stroke
				(width 0.1524)
				(type default)
			)
			(layer "F.SilkS")
		)
		(fp_line
			(start -0.7874 0.4064)
			(end -0.7874 -0.4064)
			(stroke
				(width 0.1524)
				(type default)
			)
			(layer "F.SilkS")
		)
		(fp_line
			(start 0.7874 -0.4064)
			(end 0.7874 0.4064)
			(stroke
				(width 0.1524)
				(type default)
			)
			(layer "F.SilkS")
		)
		(fp_line
			(start 0.7874 0.4064)
			(end -0.7874 0.4064)
			(stroke
				(width 0.1524)
				(type default)
			)
			(layer "F.SilkS")
		)
		(fp_line
			(start -0.67945 -0.305054)
			(end -0.12065 -0.305054)
			(stroke
				(width 0.1)
				(type default)
			)
			(layer "F.Fab")
		)
		(fp_line
			(start -0.67945 0.3048)
			(end -0.67945 -0.305054)
			(stroke
				(width 0.1)
				(type default)
			)
			(layer "F.Fab")
		)
		(fp_line
			(start -0.12065 -0.305054)
			(end -0.12065 -0.2794)
			(stroke
				(width 0.1)
				(type default)
			)
			(layer "F.Fab")
		)
		(fp_line
			(start -0.12065 -0.2794)
			(end 0.12065 -0.2794)
			(stroke
				(width 0.1)
				(type default)
			)
			(layer "F.Fab")
		)
		(fp_line
			(start -0.12065 0.2794)
			(end -0.12065 0.3048)
			(stroke
				(width 0.1)
				(type default)
			)
			(layer "F.Fab")
		)
		(fp_line
			(start -0.12065 0.3048)
			(end -0.67945 0.3048)
			(stroke
				(width 0.1)
				(type default)
			)
			(layer "F.Fab")
		)
		(fp_line
			(start 0.120396 0.2794)
			(end -0.12065 0.2794)
			(stroke
				(width 0.1)
				(type default)
			)
			(layer "F.Fab")
		)
		(fp_line
			(start 0.120396 0.3048)
			(end 0.120396 0.2794)
			(stroke
				(width 0.1)
				(type default)
			)
			(layer "F.Fab")
		)
		(fp_line
			(start 0.12065 -0.3048)
			(end 0.67945 -0.3048)
			(stroke
				(width 0.1)
				(type default)
			)
			(layer "F.Fab")
		)
		(fp_line
			(start 0.12065 -0.2794)
			(end 0.12065 -0.3048)
			(stroke
				(width 0.1)
				(type default)
			)
			(layer "F.Fab")
		)
		(fp_line
			(start 0.67945 -0.3048)
			(end 0.67945 0.3048)
			(stroke
				(width 0.1)
				(type default)
			)
			(layer "F.Fab")
		)
		(fp_line
			(start 0.67945 0.3048)
			(end 0.120396 0.3048)
			(stroke
				(width 0.1)
				(type default)
			)
			(layer "F.Fab")
		)
		(pad "1" smd circle
			(at -0.40005 0)
			(size 0 0)
			(layers "F.Cu" "F.Mask" "F.Paste")
			(net "P3V3_AUX")
		)
		(pad "2" smd circle
			(at 0.40005 0)
			(size 0 0)
			(layers "F.Cu" "F.Mask" "F.Paste")
			(net "ADC128_A0")
		)
	)
)
